(kicad_pcb
	(version 20260206)
	(generator "pcbnew")
	(generator_version "10.0")
	(general
		(thickness 1.6)
		(legacy_teardrops no)
	)
	(paper "A4")
	(title_block
		(title "Bryce Canyon_SCC_16316-1_OCP.brd")
		(comment 1 "Bryce Canyon / footprints 689-695 of 1561")
	)
	(layers
		(0 "F.Cu" signal "TOP")
		(4 "In1.Cu" signal "L2GND")
		(6 "In2.Cu" signal "L3")
		(8 "In3.Cu" signal "L4VCC")
		(10 "In4.Cu" signal "L5VCC")
		(12 "In5.Cu" signal "L6")
		(14 "In6.Cu" signal "L7GND")
		(2 "B.Cu" signal "BOTTOM")
		(9 "F.Adhes" user "F.Adhesive")
		(11 "B.Adhes" user "B.Adhesive")
		(13 "F.Paste" user "Package Geometry/Pastemask Top")
		(15 "B.Paste" user "Package Geometry/Pastemask Bottom")
		(5 "F.SilkS" user "Ref Des/Silkscreen Top")
		(7 "B.SilkS" user "Ref Des/Silkscreen Bottom")
		(1 "F.Mask" user "Board Geometry/Soldermask Top")
		(3 "B.Mask" user "Board Geometry/Soldermask Bottom")
		(17 "Dwgs.User" user "User.Drawings")
		(19 "Cmts.User" user "User.Comments")
		(21 "Eco1.User" user "User.Eco1")
		(23 "Eco2.User" user "User.Eco2")
		(25 "Edge.Cuts" user "Board Geometry/Outline")
		(27 "Margin" user)
		(31 "F.CrtYd" user "Package Geometry/Place Bound Top")
		(29 "B.CrtYd" user "Package Geometry/Place Bound Bottom")
		(35 "F.Fab" user "Ref Des/Assembly Top")
		(33 "B.Fab" user "Ref Des/Assembly Bottom")
	)
	(footprint ""
		(layer "F.Cu")
		(at 69.181472 -97.0788 -90)
		(property "Reference" "R502"
			(at 0 0 270)
			(layer "F.SilkS")
			(hide yes)
			(effects
				(font
					(size 1.27 1.27)
				)
			)
		)
		(property "Value" "619KR2F-GP"
			(at 0.064008 -3.993896 270)
			(unlocked yes)
			(layer "F.Fab")
			(hide yes)
			(effects
				(font
					(size 1.016 1.016)
					(thickness 0.1524)
				)
			)
		)
		(property "Device Type" "R402H16"
			(at 0.064008 -5.517896 270)
			(unlocked yes)
			(layer "F.Fab")
			(hide yes)
			(effects
				(font
					(size 1.016 1.016)
					(thickness 0.1524)
				)
			)
		)
		(duplicate_pad_numbers_are_jumpers no)
		(fp_line
			(start -0.508 -0.9398)
			(end -0.508 0.9398)
			(stroke
				(width 0.1524)
				(type default)
			)
			(layer "F.SilkS")
		)
		(fp_line
			(start 0.508 -0.9398)
			(end -0.508 -0.9398)
			(stroke
				(width 0.1524)
				(type default)
			)
			(layer "F.SilkS")
		)
		(fp_rect
			(start -0.508 0.9398)
			(end 0.508 -0.9398)
			(stroke
				(width 0)
				(type default)
			)
			(fill no)
			(layer "F.CrtYd")
		)
		(fp_rect
			(start -0.508 0.9398)
			(end 0.508 -0.9398)
			(stroke
				(width 0)
				(type default)
			)
			(fill no)
			(layer "F.Fab")
		)
		(pad "1" smd custom
			(at 0 -0.4445 270)
			(size 0.1397 0.1397)
			(layers "F.Cu" "F.Mask" "F.Paste")
			(net "AGND_P3V3")
			(options
				(clearance outline)
				(anchor circle)
			)
			(primitives
				(gr_poly
					(pts
						(arc
							(start -0.1778 -0.2794)
							(mid -0.249642 -0.249642)
							(end -0.2794 -0.1778)
						)
						(arc
							(start -0.2794 0.1778)
							(mid -0.249642 0.249642)
							(end -0.1778 0.2794)
						)
						(arc
							(start 0.1778 0.2794)
							(mid 0.249642 0.249642)
							(end 0.2794 0.1778)
						)
						(arc
							(start 0.2794 -0.1778)
							(mid 0.249642 -0.249642)
							(end 0.1778 -0.2794)
						)
					)
					(width 0)
					(fill yes)
				)
			)
		)
		(pad "2" smd custom
			(at 0 0.4445 270)
			(size 0.1397 0.1397)
			(layers "F.Cu" "F.Mask" "F.Paste")
			(net "P3V3_RF")
			(options
				(clearance outline)
				(anchor circle)
			)
			(primitives
				(gr_poly
					(pts
						(arc
							(start -0.1778 -0.2794)
							(mid -0.249642 -0.249642)
							(end -0.2794 -0.1778)
						)
						(arc
							(start -0.2794 0.1778)
							(mid -0.249642 0.249642)
							(end -0.1778 0.2794)
						)
						(arc
							(start 0.1778 0.2794)
							(mid 0.249642 0.249642)
							(end 0.2794 0.1778)
						)
						(arc
							(start 0.2794 -0.1778)
							(mid 0.249642 -0.249642)
							(end 0.1778 -0.2794)
						)
					)
					(width 0)
					(fill yes)
				)
			)
		)
	)
	(footprint ""
		(layer "F.Cu")
		(at 177.8508 -96.52 180)
		(property "Reference" "R489"
			(at 0 0 180)
			(layer "F.SilkS")
			(hide yes)
			(effects
				(font
					(size 1.27 1.27)
				)
			)
		)
		(property "Value" "221R2F-2-GP"
			(at 0.064008 -3.993896 180)
			(unlocked yes)
			(layer "F.Fab")
			(hide yes)
			(effects
				(font
					(size 1.016 1.016)
					(thickness 0.1524)
				)
			)
		)
		(property "Device Type" "R402H16"
			(at 0.064008 -5.517896 180)
			(unlocked yes)
			(layer "F.Fab")
			(hide yes)
			(effects
				(font
					(size 1.016 1.016)
					(thickness 0.1524)
				)
			)
		)
		(duplicate_pad_numbers_are_jumpers no)
		(fp_line
			(start 0.508 -0.9398)
			(end -0.508 -0.9398)
			(stroke
				(width 0.1524)
				(type default)
			)
			(layer "F.SilkS")
		)
		(fp_line
			(start -0.508 -0.9398)
			(end -0.508 0.9398)
			(stroke
				(width 0.1524)
				(type default)
			)
			(layer "F.SilkS")
		)
		(fp_rect
			(start -0.508 0.9398)
			(end 0.508 -0.9398)
			(stroke
				(width 0)
				(type default)
			)
			(fill no)
			(layer "F.CrtYd")
		)
		(fp_rect
			(start -0.508 0.9398)
			(end 0.508 -0.9398)
			(stroke
				(width 0)
				(type default)
			)
			(fill no)
			(layer "F.Fab")
		)
		(pad "1" smd custom
			(at 0 -0.4445 180)
			(size 0.1397 0.1397)
			(layers "F.Cu" "F.Mask" "F.Paste")
			(net "VT235_VFB")
			(options
				(clearance outline)
				(anchor circle)
			)
			(primitives
				(gr_poly
					(pts
						(arc
							(start -0.1778 -0.2794)
							(mid -0.249642 -0.249642)
							(end -0.2794 -0.1778)
						)
						(arc
							(start -0.2794 0.1778)
							(mid -0.249642 0.249642)
							(end -0.1778 0.2794)
						)
						(arc
							(start 0.1778 0.2794)
							(mid 0.249642 0.249642)
							(end 0.2794 0.1778)
						)
						(arc
							(start 0.2794 -0.1778)
							(mid 0.249642 -0.249642)
							(end 0.1778 -0.2794)
						)
					)
					(width 0)
					(fill yes)
				)
			)
		)
		(pad "2" smd custom
			(at 0 0.4445 180)
			(size 0.1397 0.1397)
			(layers "F.Cu" "F.Mask" "F.Paste")
			(net "P0V975_SEN")
			(options
				(clearance outline)
				(anchor circle)
			)
			(primitives
				(gr_poly
					(pts
						(arc
							(start -0.1778 -0.2794)
							(mid -0.249642 -0.249642)
							(end -0.2794 -0.1778)
						)
						(arc
							(start -0.2794 0.1778)
							(mid -0.249642 0.249642)
							(end -0.1778 0.2794)
						)
						(arc
							(start 0.1778 0.2794)
							(mid 0.249642 0.249642)
							(end 0.2794 0.1778)
						)
						(arc
							(start 0.2794 -0.1778)
							(mid 0.249642 -0.249642)
							(end 0.1778 -0.2794)
						)
					)
					(width 0)
					(fill yes)
				)
			)
		)
	)
	(footprint ""
		(layer "F.Cu")
		(at 26.00833 -93.622622)
		(property "Reference" "R450"
			(at 0 0 0)
			(layer "F.SilkS")
			(hide yes)
			(effects
				(font
					(size 1.27 1.27)
				)
			)
		)
		(property "Value" "1KR2F-3-GP"
			(at 0.064008 -3.993896 0)
			(unlocked yes)
			(layer "F.Fab")
			(hide yes)
			(effects
				(font
					(size 1.016 1.016)
					(thickness 0.1524)
				)
			)
		)
		(property "Device Type" "R402H16"
			(at 0.064008 -5.517896 0)
			(unlocked yes)
			(layer "F.Fab")
			(hide yes)
			(effects
				(font
					(size 1.016 1.016)
					(thickness 0.1524)
				)
			)
		)
		(duplicate_pad_numbers_are_jumpers no)
		(fp_line
			(start -0.508 -0.9398)
			(end -0.508 0.9398)
			(stroke
				(width 0.1524)
				(type default)
			)
			(layer "F.SilkS")
		)
		(fp_line
			(start 0.508 -0.9398)
			(end -0.508 -0.9398)
			(stroke
				(width 0.1524)
				(type default)
			)
			(layer "F.SilkS")
		)
		(fp_rect
			(start -0.508 0.9398)
			(end 0.508 -0.9398)
			(stroke
				(width 0)
				(type default)
			)
			(fill no)
			(layer "F.CrtYd")
		)
		(fp_rect
			(start -0.508 0.9398)
			(end 0.508 -0.9398)
			(stroke
				(width 0)
				(type default)
			)
			(fill no)
			(layer "F.Fab")
		)
		(pad "1" smd custom
			(at 0 -0.4445)
			(size 0.1397 0.1397)
			(layers "F.Cu" "F.Mask" "F.Paste")
			(net "P3V3")
			(options
				(clearance outline)
				(anchor circle)
			)
			(primitives
				(gr_poly
					(pts
						(arc
							(start -0.1778 -0.2794)
							(mid -0.249642 -0.249642)
							(end -0.2794 -0.1778)
						)
						(arc
							(start -0.2794 0.1778)
							(mid -0.249642 0.249642)
							(end -0.1778 0.2794)
						)
						(arc
							(start 0.1778 0.2794)
							(mid 0.249642 0.249642)
							(end 0.2794 0.1778)
						)
						(arc
							(start 0.2794 -0.1778)
							(mid 0.249642 -0.249642)
							(end 0.1778 -0.2794)
						)
					)
					(width 0)
					(fill yes)
				)
			)
		)
		(pad "2" smd custom
			(at 0 0.4445)
			(size 0.1397 0.1397)
			(layers "F.Cu" "F.Mask" "F.Paste")
			(net "I2C_BMC_RMT_SDA1")
			(options
				(clearance outline)
				(anchor circle)
			)
			(primitives
				(gr_poly
					(pts
						(arc
							(start -0.1778 -0.2794)
							(mid -0.249642 -0.249642)
							(end -0.2794 -0.1778)
						)
						(arc
							(start -0.2794 0.1778)
							(mid -0.249642 0.249642)
							(end -0.1778 0.2794)
						)
						(arc
							(start 0.1778 0.2794)
							(mid 0.249642 0.249642)
							(end 0.2794 0.1778)
						)
						(arc
							(start 0.2794 -0.1778)
							(mid 0.249642 -0.249642)
							(end 0.1778 -0.2794)
						)
					)
					(width 0)
					(fill yes)
				)
			)
		)
	)
	(footprint ""
		(layer "F.Cu")
		(at 184.570624 -58.470292 180)
		(property "Reference" "R222"
			(at 0 0 180)
			(layer "F.SilkS")
			(hide yes)
			(effects
				(font
					(size 1.27 1.27)
				)
			)
		)
		(property "Value" "10KR2F-2-GP"
			(at 0.064008 -3.993896 180)
			(unlocked yes)
			(layer "F.Fab")
			(hide yes)
			(effects
				(font
					(size 1.016 1.016)
					(thickness 0.1524)
				)
			)
		)
		(property "Device Type" "R402H16"
			(at 0.064008 -5.517896 180)
			(unlocked yes)
			(layer "F.Fab")
			(hide yes)
			(effects
				(font
					(size 1.016 1.016)
					(thickness 0.1524)
				)
			)
		)
		(duplicate_pad_numbers_are_jumpers no)
		(fp_line
			(start 0.508 -0.9398)
			(end -0.508 -0.9398)
			(stroke
				(width 0.1524)
				(type default)
			)
			(layer "F.SilkS")
		)
		(fp_line
			(start -0.508 -0.9398)
			(end -0.508 0.9398)
			(stroke
				(width 0.1524)
				(type default)
			)
			(layer "F.SilkS")
		)
		(fp_rect
			(start -0.508 0.9398)
			(end 0.508 -0.9398)
			(stroke
				(width 0)
				(type default)
			)
			(fill no)
			(layer "F.CrtYd")
		)
		(fp_rect
			(start -0.508 0.9398)
			(end 0.508 -0.9398)
			(stroke
				(width 0)
				(type default)
			)
			(fill no)
			(layer "F.Fab")
		)
		(pad "1" smd custom
			(at 0 -0.4445 180)
			(size 0.1397 0.1397)
			(layers "F.Cu" "F.Mask" "F.Paste")
			(net "XM_ADDR_1")
			(options
				(clearance outline)
				(anchor circle)
			)
			(primitives
				(gr_poly
					(pts
						(arc
							(start -0.1778 -0.2794)
							(mid -0.249642 -0.249642)
							(end -0.2794 -0.1778)
						)
						(arc
							(start -0.2794 0.1778)
							(mid -0.249642 0.249642)
							(end -0.1778 0.2794)
						)
						(arc
							(start 0.1778 0.2794)
							(mid 0.249642 0.249642)
							(end 0.2794 0.1778)
						)
						(arc
							(start 0.2794 -0.1778)
							(mid 0.249642 -0.249642)
							(end 0.1778 -0.2794)
						)
					)
					(width 0)
					(fill yes)
				)
			)
		)
		(pad "2" smd custom
			(at 0 0.4445 180)
			(size 0.1397 0.1397)
			(layers "F.Cu" "F.Mask" "F.Paste")
			(net "GND")
			(options
				(clearance outline)
				(anchor circle)
			)
			(primitives
				(gr_poly
					(pts
						(arc
							(start -0.1778 -0.2794)
							(mid -0.249642 -0.249642)
							(end -0.2794 -0.1778)
						)
						(arc
							(start -0.2794 0.1778)
							(mid -0.249642 0.249642)
							(end -0.1778 0.2794)
						)
						(arc
							(start 0.1778 0.2794)
							(mid 0.249642 0.249642)
							(end 0.2794 0.1778)
						)
						(arc
							(start 0.2794 -0.1778)
							(mid 0.249642 -0.249642)
							(end 0.1778 -0.2794)
						)
					)
					(width 0)
					(fill yes)
				)
			)
		)
	)
	(footprint ""
		(layer "F.Cu")
		(at 12.319 -98.425 90)
		(property "Reference" "C736"
			(at 0 0 90)
			(layer "F.SilkS")
			(hide yes)
			(effects
				(font
					(size 1.27 1.27)
				)
			)
		)
		(property "Value" "SCD1U16V2KX-3GP"
			(at 1.1811 -2.7051 90)
			(unlocked yes)
			(layer "F.Fab")
			(hide yes)
			(effects
				(font
					(size 1.016 1.016)
					(thickness 0.1524)
				)
			)
		)
		(property "Device Type" "C402H22"
			(at 1.1811 -4.2291 90)
			(unlocked yes)
			(layer "F.Fab")
			(hide yes)
			(effects
				(font
					(size 1.016 1.016)
					(thickness 0.1524)
				)
			)
		)
		(duplicate_pad_numbers_are_jumpers no)
		(fp_rect
			(start -0.4318 0.9525)
			(end 0.4318 -0.9525)
			(stroke
				(width 0)
				(type default)
			)
			(fill no)
			(layer "F.CrtYd")
		)
		(fp_rect
			(start -0.4318 0.9525)
			(end 0.4318 -0.9525)
			(stroke
				(width 0)
				(type default)
			)
			(fill no)
			(layer "F.Fab")
		)
		(pad "1" smd custom
			(at 0 -0.4445 90)
			(size 0.1524 0.1524)
			(layers "F.Cu" "F.Mask" "F.Paste")
			(net "U120_EN")
			(options
				(clearance outline)
				(anchor circle)
			)
			(primitives
				(gr_poly
					(pts
						(arc
							(start 0.3048 -0.2032)
							(mid 0.275042 -0.275042)
							(end 0.2032 -0.3048)
						)
						(arc
							(start -0.2032 -0.3048)
							(mid -0.275042 -0.275042)
							(end -0.3048 -0.2032)
						)
						(arc
							(start -0.3048 0.2032)
							(mid -0.275042 0.275042)
							(end -0.2032 0.3048)
						)
						(arc
							(start 0.2032 0.3048)
							(mid 0.275042 0.275042)
							(end 0.3048 0.2032)
						)
					)
					(width 0)
					(fill yes)
				)
			)
		)
		(pad "2" smd custom
			(at 0 0.4445 90)
			(size 0.1524 0.1524)
			(layers "F.Cu" "F.Mask" "F.Paste")
			(net "GND")
			(options
				(clearance outline)
				(anchor circle)
			)
			(primitives
				(gr_poly
					(pts
						(arc
							(start 0.3048 -0.2032)
							(mid 0.275042 -0.275042)
							(end 0.2032 -0.3048)
						)
						(arc
							(start -0.2032 -0.3048)
							(mid -0.275042 -0.275042)
							(end -0.3048 -0.2032)
						)
						(arc
							(start -0.3048 0.2032)
							(mid -0.275042 0.275042)
							(end -0.2032 0.3048)
						)
						(arc
							(start 0.2032 0.3048)
							(mid 0.275042 0.275042)
							(end 0.3048 0.2032)
						)
					)
					(width 0)
					(fill yes)
				)
			)
		)
	)
	(footprint ""
		(layer "F.Cu")
		(at 133.72973 -44.702984 180)
		(property "Reference" "C42"
			(at 0 0 180)
			(layer "F.SilkS")
			(hide yes)
			(effects
				(font
					(size 1.27 1.27)
				)
			)
		)
		(property "Value" "SCD01U16V1KX-GP"
			(at -2.8321 -1.7399 180)
			(unlocked yes)
			(layer "F.Fab")
			(hide yes)
			(effects
				(font
					(size 1.016 1.016)
					(thickness 0.1524)
				)
			)
		)
		(property "Device Type" "C0201H13"
			(at -2.8321 -3.2639 180)
			(unlocked yes)
			(layer "F.Fab")
			(hide yes)
			(effects
				(font
					(size 1.016 1.016)
					(thickness 0.1524)
				)
			)
		)
		(duplicate_pad_numbers_are_jumpers no)
		(fp_rect
			(start -0.2794 0.6477)
			(end 0.2794 -0.6477)
			(stroke
				(width 0)
				(type default)
			)
			(fill no)
			(layer "F.CrtYd")
		)
		(fp_rect
			(start -0.2794 0.6477)
			(end 0.2794 -0.6477)
			(stroke
				(width 0)
				(type default)
			)
			(fill no)
			(layer "F.Fab")
		)
		(pad "1" smd custom
			(at 0 -0.2794 180)
			(size 0.0762 0.0762)
			(layers "F.Cu" "F.Mask" "F.Paste")
			(net "PHY_IOC_TO_SCC_43_DN")
			(options
				(clearance outline)
				(anchor circle)
			)
			(primitives
				(gr_poly
					(pts
						(arc
							(start 0.1524 -0.127)
							(mid 0.137521 -0.162921)
							(end 0.1016 -0.1778)
						)
						(arc
							(start -0.1016 -0.1778)
							(mid -0.137521 -0.162921)
							(end -0.1524 -0.127)
						)
						(arc
							(start -0.1524 0.127)
							(mid -0.137521 0.162921)
							(end -0.1016 0.1778)
						)
						(arc
							(start 0.1016 0.1778)
							(mid 0.137521 0.162921)
							(end 0.1524 0.127)
						)
					)
					(width 0)
					(fill yes)
				)
			)
		)
		(pad "2" smd custom
			(at 0 0.2794 180)
			(size 0.0762 0.0762)
			(layers "F.Cu" "F.Mask" "F.Paste")
			(net "PHY_IOC_TO_SCC_C_43_DN")
			(options
				(clearance outline)
				(anchor circle)
			)
			(primitives
				(gr_poly
					(pts
						(arc
							(start 0.1524 -0.127)
							(mid 0.137521 -0.162921)
							(end 0.1016 -0.1778)
						)
						(arc
							(start -0.1016 -0.1778)
							(mid -0.137521 -0.162921)
							(end -0.1524 -0.127)
						)
						(arc
							(start -0.1524 0.127)
							(mid -0.137521 0.162921)
							(end -0.1016 0.1778)
						)
						(arc
							(start 0.1016 0.1778)
							(mid 0.137521 0.162921)
							(end 0.1524 0.127)
						)
					)
					(width 0)
					(fill yes)
				)
			)
		)
	)
	(footprint ""
		(layer "F.Cu")
		(at 129.648458 -46.400974 90)
		(property "Reference" "VIA11"
			(at 0 0 90)
			(layer "F.SilkS")
			(hide yes)
			(effects
				(font
					(size 1.27 1.27)
				)
			)
		)
		(property "Value" "100OHM-8L-1D6MM-L13-GP"
			(at 3.2893 0.0508 90)
			(unlocked yes)
			(layer "F.Fab")
			(hide yes)
			(effects
				(font
					(size 1.016 1.016)
					(thickness 0.1524)
				)
			)
		)
		(property "Device Type" "VIA-PCIE-4P-409091"
			(at 3.2893 -1.4732 90)
			(unlocked yes)
			(layer "F.Fab")
			(hide yes)
			(effects
				(font
					(size 1.016 1.016)
					(thickness 0.1524)
				)
			)
		)
		(duplicate_pad_numbers_are_jumpers no)
		(fp_rect
			(start -2.0447 0.4572)
			(end 2.0447 -0.4572)
			(stroke
				(width 0)
				(type default)
			)
			(fill no)
			(layer "F.CrtYd")
		)
		(fp_rect
			(start -2.0447 0.4572)
			(end 2.0447 -0.4572)
			(stroke
				(width 0)
				(type default)
			)
			(fill no)
			(layer "F.Fab")
		)
		(pad "1" thru_hole circle
			(at -1.5875 0 90)
			(size 0.508 0.508)
			(drill 0.254)
			(layers "*.Cu" "*.Mask")
			(remove_unused_layers no)
			(net "GND")
			(clearance 0.2032)
			(thermal_gap 0.2032)
		)
		(pad "2" thru_hole circle
			(at -0.5715 0 90)
			(size 0.508 0.508)
			(drill 0.254)
			(layers "*.Cu" "*.Mask")
			(remove_unused_layers no)
			(net "PHY_IOC_TO_SCC_C_42_DP")
			(clearance 0.2032)
			(thermal_gap 0.2032)
		)
		(pad "3" thru_hole circle
			(at 0.5715 0 90)
			(size 0.508 0.508)
			(drill 0.254)
			(layers "*.Cu" "*.Mask")
			(remove_unused_layers no)
			(net "PHY_IOC_TO_SCC_C_42_DN")
			(clearance 0.2032)
			(thermal_gap 0.2032)
		)
		(pad "4" thru_hole circle
			(at 1.5875 0 90)
			(size 0.508 0.508)
			(drill 0.254)
			(layers "*.Cu" "*.Mask")
			(remove_unused_layers no)
			(net "GND")
			(clearance 0.2032)
			(thermal_gap 0.2032)
		)
	)
)
